# T6G (Grand Teton) — schematic netlist excerpt (pin names and nets, part order shuffled) for the footprints in the layout excerpt that follows; sources: Cadence DE-HDL packaged netlist, KiCad conversion of 04192023_DAF0TMB3IC0_F0TG_MB_C_brd_V02_OCP.brd

R186  Q_RES  33 5% CHIP  pkg 0402LF  page 81 : A = FM_CPU0_FORCE_SELFREFRESH ; B = CPU0_FORCE_SELFREFRESH
C2138  Q_CAP  22UF 4V 20% X6S  pkg C0402  page 68 : A = PVDD11_S3_P0 ; B = GND

(kicad_pcb
	(version 20260206)
	(generator "pcbnew")
	(generator_version "10.0")
	(general
		(thickness 1.6)
		(legacy_teardrops no)
	)
	(paper "A4")
	(title_block
		(title "04192023_DAF0TMB3IC0_F0TG_MB_C_brd_V02_OCP.brd")
		(comment 1 "Grand Teton / footprints 6661-6662 of 8354")
	)
	(layers
		(0 "F.Cu" signal "TOP")
		(4 "In1.Cu" signal "GND")
		(6 "In2.Cu" signal "IN1")
		(8 "In3.Cu" signal "GND1")
		(10 "In4.Cu" signal "IN2")
		(12 "In5.Cu" signal "GND2")
		(14 "In6.Cu" signal "IN3")
		(16 "In7.Cu" signal "GND3")
		(18 "In8.Cu" signal "VCC")
		(20 "In9.Cu" signal "VCC1")
		(22 "In10.Cu" signal "GND4")
		(24 "In11.Cu" signal "IN4")
		(26 "In12.Cu" signal "GND5")
		(28 "In13.Cu" signal "IN5")
		(30 "In14.Cu" signal "GND6")
		(32 "In15.Cu" signal "IN6")
		(34 "In16.Cu" signal "GND7")
		(2 "B.Cu" signal "BOTTOM")
		(9 "F.Adhes" user "F.Adhesive")
		(11 "B.Adhes" user "B.Adhesive")
		(13 "F.Paste" user "Package Geometry/Pastemask Top")
		(15 "B.Paste" user "Package Geometry/Pastemask Bottom")
		(5 "F.SilkS" user "Ref Des/Silkscreen Top")
		(7 "B.SilkS" user "Ref Des/Silkscreen Bottom")
		(1 "F.Mask" user "Board Geometry/Soldermask Top")
		(3 "B.Mask" user "Board Geometry/Soldermask Bottom")
		(17 "Dwgs.User" user "User.Drawings")
		(19 "Cmts.User" user "User.Comments")
		(21 "Eco1.User" user "User.Eco1")
		(23 "Eco2.User" user "User.Eco2")
		(25 "Edge.Cuts" user "Board Geometry/Outline")
		(27 "Margin" user)
		(31 "F.CrtYd" user "Package Geometry/Place Bound Top")
		(29 "B.CrtYd" user "Package Geometry/Place Bound Bottom")
		(35 "F.Fab" user "Ref Des/Assembly Top")
		(33 "B.Fab" user "Ref Des/Assembly Bottom")
	)
	(footprint ""
		(layer "B.Cu")
		(at 194.094608 -126.833376 -90)
		(property "Reference" "R186"
			(at 0 0 90)
			(layer "B.SilkS")
			(hide yes)
			(effects
				(font
					(size 1.27 1.27)
				)
				(justify mirror)
			)
		)
		(property "Value" ""
			(at 0 0 90)
			(layer "B.Fab")
			(effects
				(font
					(size 1.27 1.27)
				)
				(justify mirror)
			)
		)
		(duplicate_pad_numbers_are_jumpers no)
		(fp_line
			(start -0.7874 0.4064)
			(end 0.7874 0.4064)
			(stroke
				(width 0.1524)
				(type default)
			)
			(layer "B.SilkS")
		)
		(fp_line
			(start 0.7874 0.4064)
			(end 0.7874 -0.4064)
			(stroke
				(width 0.1524)
				(type default)
			)
			(layer "B.SilkS")
		)
		(fp_line
			(start -0.7874 -0.4064)
			(end -0.7874 0.4064)
			(stroke
				(width 0.1524)
				(type default)
			)
			(layer "B.SilkS")
		)
		(fp_line
			(start 0.7874 -0.4064)
			(end -0.7874 -0.4064)
			(stroke
				(width 0.1524)
				(type default)
			)
			(layer "B.SilkS")
		)
		(fp_line
			(start -0.67945 0.3048)
			(end -0.120396 0.3048)
			(stroke
				(width 0.1)
				(type default)
			)
			(layer "B.Fab")
		)
		(fp_line
			(start -0.120396 0.3048)
			(end -0.120396 0.2794)
			(stroke
				(width 0.1)
				(type default)
			)
			(layer "B.Fab")
		)
		(fp_line
			(start 0.12065 0.3048)
			(end 0.67945 0.3048)
			(stroke
				(width 0.1)
				(type default)
			)
			(layer "B.Fab")
		)
		(fp_line
			(start 0.67945 0.3048)
			(end 0.67945 -0.305054)
			(stroke
				(width 0.1)
				(type default)
			)
			(layer "B.Fab")
		)
		(fp_line
			(start -0.120396 0.2794)
			(end 0.12065 0.2794)
			(stroke
				(width 0.1)
				(type default)
			)
			(layer "B.Fab")
		)
		(fp_line
			(start 0.12065 0.2794)
			(end 0.12065 0.3048)
			(stroke
				(width 0.1)
				(type default)
			)
			(layer "B.Fab")
		)
		(fp_line
			(start -0.12065 -0.2794)
			(end -0.12065 -0.3048)
			(stroke
				(width 0.1)
				(type default)
			)
			(layer "B.Fab")
		)
		(fp_line
			(start 0.12065 -0.2794)
			(end -0.12065 -0.2794)
			(stroke
				(width 0.1)
				(type default)
			)
			(layer "B.Fab")
		)
		(fp_line
			(start -0.67945 -0.3048)
			(end -0.67945 0.3048)
			(stroke
				(width 0.1)
				(type default)
			)
			(layer "B.Fab")
		)
		(fp_line
			(start -0.12065 -0.3048)
			(end -0.67945 -0.3048)
			(stroke
				(width 0.1)
				(type default)
			)
			(layer "B.Fab")
		)
		(fp_line
			(start 0.12065 -0.305054)
			(end 0.12065 -0.2794)
			(stroke
				(width 0.1)
				(type default)
			)
			(layer "B.Fab")
		)
		(fp_line
			(start 0.67945 -0.305054)
			(end 0.12065 -0.305054)
			(stroke
				(width 0.1)
				(type default)
			)
			(layer "B.Fab")
		)
		(pad "1" smd circle
			(at 0.40005 0 90)
			(size 0 0)
			(layers "B.Cu" "B.Mask" "B.Paste")
			(net "FM_CPU0_FORCE_SELFREFRESH")
		)
		(pad "2" smd circle
			(at -0.40005 0 90)
			(size 0 0)
			(layers "B.Cu" "B.Mask" "B.Paste")
			(net "CPU0_FORCE_SELFREFRESH")
		)
	)
	(footprint ""
		(layer "B.Cu")
		(at 363.804454 -264.35431)
		(property "Reference" "C2138"
			(at 0 0 0)
			(layer "B.SilkS")
			(hide yes)
			(effects
				(font
					(size 1.27 1.27)
				)
				(justify mirror)
			)
		)
		(property "Value" ""
			(at 0 0 0)
			(layer "B.Fab")
			(effects
				(font
					(size 1.27 1.27)
				)
				(justify mirror)
			)
		)
		(duplicate_pad_numbers_are_jumpers no)
		(fp_line
			(start -0.7874 -0.4064)
			(end -0.7874 0.4064)
			(stroke
				(width 0.1524)
				(type default)
			)
			(layer "B.SilkS")
		)
		(fp_line
			(start -0.7874 0.4064)
			(end 0.7874 0.4064)
			(stroke
				(width 0.1524)
				(type default)
			)
			(layer "B.SilkS")
		)
		(fp_line
			(start 0.7874 -0.4064)
			(end -0.7874 -0.4064)
			(stroke
				(width 0.1524)
				(type default)
			)
			(layer "B.SilkS")
		)
		(fp_line
			(start 0.7874 0.4064)
			(end 0.7874 -0.4064)
			(stroke
				(width 0.1524)
				(type default)
			)
			(layer "B.SilkS")
		)
		(fp_line
			(start -0.67945 -0.3048)
			(end -0.67945 0.3048)
			(stroke
				(width 0.1)
				(type default)
			)
			(layer "B.Fab")
		)
		(fp_line
			(start -0.67945 0.3048)
			(end -0.120396 0.3048)
			(stroke
				(width 0.1)
				(type default)
			)
			(layer "B.Fab")
		)
		(fp_line
			(start -0.12065 -0.3048)
			(end -0.67945 -0.3048)
			(stroke
				(width 0.1)
				(type default)
			)
			(layer "B.Fab")
		)
		(fp_line
			(start -0.12065 -0.2794)
			(end -0.12065 -0.3048)
			(stroke
				(width 0.1)
				(type default)
			)
			(layer "B.Fab")
		)
		(fp_line
			(start -0.120396 0.2794)
			(end 0.12065 0.2794)
			(stroke
				(width 0.1)
				(type default)
			)
			(layer "B.Fab")
		)
		(fp_line
			(start -0.120396 0.3048)
			(end -0.120396 0.2794)
			(stroke
				(width 0.1)
				(type default)
			)
			(layer "B.Fab")
		)
		(fp_line
			(start 0.12065 -0.305054)
			(end 0.12065 -0.2794)
			(stroke
				(width 0.1)
				(type default)
			)
			(layer "B.Fab")
		)
		(fp_line
			(start 0.12065 -0.2794)
			(end -0.12065 -0.2794)
			(stroke
				(width 0.1)
				(type default)
			)
			(layer "B.Fab")
		)
		(fp_line
			(start 0.12065 0.2794)
			(end 0.12065 0.3048)
			(stroke
				(width 0.1)
				(type default)
			)
			(layer "B.Fab")
		)
		(fp_line
			(start 0.12065 0.3048)
			(end 0.67945 0.3048)
			(stroke
				(width 0.1)
				(type default)
			)
			(layer "B.Fab")
		)
		(fp_line
			(start 0.67945 -0.305054)
			(end 0.12065 -0.305054)
			(stroke
				(width 0.1)
				(type default)
			)
			(layer "B.Fab")
		)
		(fp_line
			(start 0.67945 0.3048)
			(end 0.67945 -0.305054)
			(stroke
				(width 0.1)
				(type default)
			)
			(layer "B.Fab")
		)
		(pad "1" smd circle
			(at 0.40005 0 180)
			(size 0 0)
			(layers "B.Cu" "B.Mask" "B.Paste")
			(net "PVDD11_S3_P0")
		)
		(pad "2" smd circle
			(at -0.40005 0 180)
			(size 0 0)
			(layers "B.Cu" "B.Mask" "B.Paste")
			(net "GND")
		)
	)
)
